# BASEBOARD_FAB2 (Tioga Pass) — schematic netlist excerpt (pin names and nets, part order shuffled) for the footprints in the layout excerpt that follows; sources: Cadence DE-HDL packaged netlist, KiCad conversion of Wiwynn_Tioga_Pass_MB.brd

J8G1  SCONN200_H68296001  CONN  pkg SM  page 108
  IO1  = P12V
  IO2  = P12V
  IO3  = P12V
  IO4  = P12V
  IO5  = P12V
  IO6  = P12V
  IO7  = P12V
  IO8  = P12V
  IO9  = P12V
  IO10  = P12V
  IO11  = P12V
  IO12  = P12V
  IO13  = GND
  IO14  = GND
  IO15  = SMB_SLOTX24_STBY_LVC3_SDA_R2
  IO16  = IRQ_OOB_MGMT_RISER_ALERT_N
  IO17  = SMB_SLOTX24_STBY_LVC3_SCL_R2
  IO18  = FM_SLT_CFG1
  IO19  = FM_SLT_CFG0
  IO20  = FM_PWRBRK_SLOT_N
  IO21  = P3V3
  IO22  = P3V3
  IO23  = P3V3
  IO24  = P3V3
  IO25  = P3V3_STBY
  IO26  = GND
  IO27  = PU_PCH_TLS_ENABLE_STRAP
  IO28  = FM_PE_SLOTX24_WAKE_N
  IO29  = RST_PCIE_RISER1_PERST_R_N
  IO30  = SMB_HOST_STBY_LVC3_SDA_R5
  IO31  = GND
  IO32  = SMB_HOST_STBY_LVC3_SCL_R5
  IO33  = CLK_100M_PCH_SLOTX24_S5_DP
  IO34  = GND
  IO35  = CLK_100M_PCH_SLOTX24_S5_DN
  IO36  = CLK_100M_PCH_SLOTX24_S4_DP
  IO37  = GND
  IO38  = CLK_100M_PCH_SLOTX24_S4_DN
  IO39  = CLK_100M_PCH_SLOTX24_S0_DP
  IO40  = GND
  IO41  = CLK_100M_PCH_SLOTX24_S0_DN
  IO42  = CLK_100M_PCH_SLOTX24_S1_DP
  IO43  = GND
  IO44  = CLK_100M_PCH_SLOTX24_S1_DN
  IO45  = CLK_100M_PCH_SLOTX24_S3_DP
  IO46  = GND
  IO47  = CLK_100M_PCH_SLOTX24_S3_DN
  IO48  = CLK_100M_PCH_SLOTX24_S2_DP
  IO49  = GND
  IO50  = CLK_100M_PCH_SLOTX24_S2_DN
  IO51  = P3E_CPU0_PE1_PCH_CON_TXN<15>
  IO52  = GND
  IO53  = P3E_CPU0_PE1_PCH_CON_TXP<15>
  IO54  = P3E_CPU0_PE1_PCH_CON_RXN<15>
  IO55  = GND
  IO56  = P3E_CPU0_PE1_PCH_CON_RXP<15>
  IO57  = P3E_CPU0_PE1_PCH_CON_TXP<14>
  IO58  = GND
  IO59  = P3E_CPU0_PE1_PCH_CON_TXN<14>
  IO60  = P3E_CPU0_PE1_PCH_CON_RXN<14>
  IO61  = GND
  IO62  = P3E_CPU0_PE1_PCH_CON_RXP<14>
  IO63  = TP_SLOTX24_RSVD63
  IO64  = GND
  IO65  = GND
  IO66  = TP_SLOTX24_RSVD66
  IO67  = P3E_CPU0_PE1_PCH_CON_TXN<13>
  IO68  = GND
  IO69  = P3E_CPU0_PE1_PCH_CON_TXP<13>
  IO70  = P3E_CPU0_PE1_PCH_CON_RXN<13>
  IO71  = GND
  IO72  = P3E_CPU0_PE1_PCH_CON_RXP<13>
  IO73  = P3E_CPU0_PE1_PCH_CON_TXN<12>
  IO74  = GND
  IO75  = P3E_CPU0_PE1_PCH_CON_TXP<12>
  IO76  = P3E_CPU0_PE1_PCH_CON_RXN<12>
  IO77  = GND
  IO78  = P3E_CPU0_PE1_PCH_CON_RXP<12>
  IO79  = P3E_CPU0_PE1_PCH_CON_TXN<11>
  IO80  = GND
  IO81  = P3E_CPU0_PE1_PCH_CON_TXP<11>
  IO82  = P3E_CPU0_PE1_PCH_CON_RXN<11>
  IO83  = GND
  IO84  = P3E_CPU0_PE1_PCH_CON_RXP<11>
  IO85  = P3E_CPU0_PE1_PCH_CON_TXN<10>
  IO86  = GND
  IO87  = P3E_CPU0_PE1_PCH_CON_TXP<10>
  IO88  = P3E_CPU0_PE1_PCH_CON_RXN<10>
  IO89  = GND
  IO90  = P3E_CPU0_PE1_PCH_CON_RXP<10>
  IO91  = P3E_CPU0_PE1_PCH_CON_TXN<9>
  IO92  = GND
  IO93  = P3E_CPU0_PE1_PCH_CON_TXP<9>
  IO94  = P3E_CPU0_PE1_PCH_CON_RXN<9>
  IO95  = GND
  IO96  = P3E_CPU0_PE1_PCH_CON_RXP<9>
  IO97  = P3E_CPU0_PE1_PCH_CON_TXN<8>
  IO98  = GND
  IO99  = P3E_CPU0_PE1_PCH_CON_TXP<8>
  IO100  = P3E_CPU0_PE1_PCH_CON_RXN<8>
  IO101  = GND
  IO102  = P3E_CPU0_PE1_PCH_CON_RXP<8>
  IO103  = P3E_CPU0_PE1_SS_C_TXP<7>
  IO104  = GND
  IO105  = P3E_CPU0_PE1_SS_C_TXN<7>
  IO106  = P3E_CPU0_PE1_SS_R_RXN<7>
  IO107  = GND
  IO108  = P3E_CPU0_PE1_SS_R_RXP<7>
  IO109  = P3E_CPU0_PE1_SS_C_TXN<6>
  IO110  = GND
  IO111  = P3E_CPU0_PE1_SS_C_TXP<6>
  IO112  = P3E_CPU0_PE1_SS_R_RXN<6>
  IO113  = GND
  IO114  = P3E_CPU0_PE1_SS_R_RXP<6>
  IO115  = P3E_CPU0_PE1_SS_C_TXN<5>
  IO116  = GND
  IO117  = P3E_CPU0_PE1_SS_C_TXP<5>
  IO118  = P3E_CPU0_PE1_SS_R_RXN<5>
  IO119  = GND
  IO120  = P3E_CPU0_PE1_SS_R_RXP<5>
  IO121  = P3E_CPU0_PE1_SS_C_TXN<4>
  IO122  = GND
  IO123  = P3E_CPU0_PE1_SS_C_TXP<4>
  IO124  = P3E_CPU0_PE1_SS_R_RXN<4>
  IO125  = GND
  IO126  = P3E_CPU0_PE1_SS_R_RXP<4>
  IO127  = P3E_CPU0_PE1_SS_C_TXN<3>
  IO128  = GND
  IO129  = P3E_CPU0_PE1_SS_C_TXP<3>
  IO130  = P3E_CPU0_PE1_SS_R_RXN<3>
  IO131  = GND
  IO132  = P3E_CPU0_PE1_SS_R_RXP<3>
  IO133  = P3E_CPU0_PE1_SS_C_TXN<2>
  IO134  = GND
  IO135  = P3E_CPU0_PE1_SS_C_TXP<2>
  IO136  = P3E_CPU0_PE1_SS_R_RXN<2>
  IO137  = GND
  IO138  = P3E_CPU0_PE1_SS_R_RXP<2>
  IO139  = P3E_CPU0_PE1_SS_C_TXN<1>
  IO140  = GND
  IO141  = P3E_CPU0_PE1_SS_C_TXP<1>
  IO142  = P3E_CPU0_PE1_SS_R_RXN<1>
  IO143  = GND
  IO144  = P3E_CPU0_PE1_SS_R_RXP<1>
  IO145  = P3E_CPU0_PE1_SS_C_TXN<0>
  IO146  = GND
  IO147  = P3E_CPU0_PE1_SS_C_TXP<0>
  IO148  = P3E_CPU0_PE1_SS_R_RXN<0>
  IO149  = GND
  IO150  = P3E_CPU0_PE1_SS_R_RXP<0>
  IO151  = P3E_CPU0_PE2_SS_C_TXN<0>
  IO152  = GND
  IO153  = P3E_CPU0_PE2_SS_C_TXP<0>
  IO154  = P3E_CPU0_PE2_SS_RXN<0>
  IO155  = GND
  IO156  = P3E_CPU0_PE2_SS_RXP<0>
  IO157  = P3E_CPU0_PE2_SS_C_TXP<1>
  IO158  = GND
  IO159  = P3E_CPU0_PE2_SS_C_TXN<1>
  IO160  = P3E_CPU0_PE2_SS_RXN<1>
  IO161  = GND
  IO162  = P3E_CPU0_PE2_SS_RXP<1>
  IO163  = P3E_CPU0_PE2_SS_C_TXN<2>
  IO164  = GND
  IO165  = P3E_CPU0_PE2_SS_C_TXP<2>
  IO166  = P3E_CPU0_PE2_SS_RXN<2>
  IO167  = GND
  IO168  = P3E_CPU0_PE2_SS_RXP<2>
  IO169  = P3E_CPU0_PE2_SS_C_TXN<3>
  IO170  = GND
  IO171  = P3E_CPU0_PE2_SS_C_TXP<3>
  IO172  = P3E_CPU0_PE2_SS_RXN<3>
  IO173  = GND
  IO174  = P3E_CPU0_PE2_SS_RXP<3>
  IO175  = P3E_CPU0_PE2_SS_C_TXN<4>
  IO176  = GND
  IO177  = P3E_CPU0_PE2_SS_C_TXP<4>
  IO178  = P3E_CPU0_PE2_SS_RXN<4>
  IO179  = GND
  IO180  = P3E_CPU0_PE2_SS_RXP<4>
  IO181  = P3E_CPU0_PE2_SS_C_TXN<5>
  IO182  = GND
  IO183  = P3E_CPU0_PE2_SS_C_TXP<5>
  IO184  = P3E_CPU0_PE2_SS_RXN<5>
  IO185  = GND
  IO186  = P3E_CPU0_PE2_SS_RXP<5>
  IO187  = P3E_CPU0_PE2_SS_C_TXN<6>
  IO188  = GND
  IO189  = P3E_CPU0_PE2_SS_C_TXP<6>
  IO190  = P3E_CPU0_PE2_SS_RXP<6>
  IO191  = GND
  IO192  = P3E_CPU0_PE2_SS_RXN<6>
  IO193  = P3E_CPU0_PE2_SS_C_TXN<7>
  IO194  = GND
  IO195  = P3E_CPU0_PE2_SS_C_TXP<7>
  IO196  = P3E_CPU0_PE2_SS_RXN<7>
  IO197  = GND
  IO198  = P3E_CPU0_PE2_SS_RXP<7>
  IO199  = FM_PRSNT_2_6_N
  IO200  = GND
  MH1  = GND
  MH2  = GND

(kicad_pcb
	(version 20260206)
	(generator "pcbnew")
	(generator_version "10.0")
	(general
		(thickness 1.6)
		(legacy_teardrops no)
	)
	(paper "A4")
	(title_block
		(title "Wiwynn_Tioga_Pass_MB.brd")
		(comment 1 "Tioga Pass / footprint 949 of 4770 (J8G1), pads 1-48 of 204")
	)
	(layers
		(0 "F.Cu" signal "TOP")
		(4 "In1.Cu" signal "L2GND")
		(6 "In2.Cu" signal "L3")
		(8 "In3.Cu" signal "L4GND")
		(10 "In4.Cu" signal "L5")
		(12 "In5.Cu" signal "L6GND")
		(14 "In6.Cu" signal "L7VCC")
		(16 "In7.Cu" signal "L8VCC")
		(18 "In8.Cu" signal "L9GND")
		(20 "In9.Cu" signal "L10")
		(22 "In10.Cu" signal "L11GND")
		(24 "In11.Cu" signal "L12")
		(26 "In12.Cu" signal "L13GND")
		(2 "B.Cu" signal "BOTTOM")
		(9 "F.Adhes" user "F.Adhesive")
		(11 "B.Adhes" user "B.Adhesive")
		(13 "F.Paste" user "Package Geometry/Pastemask Top")
		(15 "B.Paste" user "Package Geometry/Pastemask Bottom")
		(5 "F.SilkS" user "Ref Des/Silkscreen Top")
		(7 "B.SilkS" user "Ref Des/Silkscreen Bottom")
		(1 "F.Mask" user "Board Geometry/Soldermask Top")
		(3 "B.Mask" user "Board Geometry/Soldermask Bottom")
		(17 "Dwgs.User" user "User.Drawings")
		(19 "Cmts.User" user "User.Comments")
		(21 "Eco1.User" user "User.Eco1")
		(23 "Eco2.User" user "User.Eco2")
		(25 "Edge.Cuts" user "Board Geometry/Outline")
		(27 "Margin" user)
		(31 "F.CrtYd" user "Package Geometry/Place Bound Top")
		(29 "B.CrtYd" user "Package Geometry/Place Bound Bottom")
		(35 "F.Fab" user "Ref Des/Assembly Top")
		(33 "B.Fab" user "Ref Des/Assembly Bottom")
	)
	(footprint ""
		(layer "F.Cu")
		(at 474.080078 -7.789672 -90)
		(property "Reference" "J8G1"
			(at -3.126486 25.39111 0)
			(unlocked yes)
			(layer "F.SilkS")
			(effects
				(font
					(size 0.7874 0.5842)
					(thickness 0.1524)
				)
				(justify left)
			)
		)
		(property "Value" ""
			(at 0 0 270)
			(layer "F.Fab")
			(effects
				(font
					(size 1.27 1.27)
				)
			)
		)
		(duplicate_pad_numbers_are_jumpers no)
		(pad "" np_thru_hole circle
			(at 0.201676 -1.495044 270)
			(size 0.254 0.254)
			(drill 1.27)
			(layers "*.Cu" "*.Mask")
			(clearance 0.8255)
			(thermal_gap 0.8255)
		)
		(pad "" np_thru_hole circle
			(at 1.7018 83.904836 270)
			(size 0.254 0.254)
			(drill 1.27)
			(layers "*.Cu" "*.Mask")
			(clearance 0.8255)
			(thermal_gap 0.8255)
		)
		(pad "1" smd rect
			(at 0 0 270)
			(size 1.1938 0.508)
			(layers "F.Cu" "F.Mask" "F.Paste")
			(net "P12V")
		)
		(pad "2" smd rect
			(at 3.4036 0 270)
			(size 1.1938 0.508)
			(layers "F.Cu" "F.Mask" "F.Paste")
			(net "P12V")
		)
		(pad "3" smd rect
			(at 0 0.8001 270)
			(size 1.1938 0.508)
			(layers "F.Cu" "F.Mask" "F.Paste")
			(net "P12V")
		)
		(pad "4" smd rect
			(at 3.4036 0.8001 270)
			(size 1.1938 0.508)
			(layers "F.Cu" "F.Mask" "F.Paste")
			(net "P12V")
		)
		(pad "5" smd rect
			(at 0 1.6002 270)
			(size 1.1938 0.508)
			(layers "F.Cu" "F.Mask" "F.Paste")
			(net "P12V")
		)
		(pad "6" smd rect
			(at 3.4036 1.6002 270)
			(size 1.1938 0.508)
			(layers "F.Cu" "F.Mask" "F.Paste")
			(net "P12V")
		)
		(pad "7" smd rect
			(at 0 2.4003 270)
			(size 1.1938 0.508)
			(layers "F.Cu" "F.Mask" "F.Paste")
			(net "P12V")
		)
		(pad "8" smd rect
			(at 3.4036 2.4003 270)
			(size 1.1938 0.508)
			(layers "F.Cu" "F.Mask" "F.Paste")
			(net "P12V")
		)
		(pad "9" smd rect
			(at 0 3.2004 270)
			(size 1.1938 0.508)
			(layers "F.Cu" "F.Mask" "F.Paste")
			(net "P12V")
		)
		(pad "10" smd rect
			(at 3.4036 3.2004 270)
			(size 1.1938 0.508)
			(layers "F.Cu" "F.Mask" "F.Paste")
			(net "P12V")
		)
		(pad "11" smd rect
			(at 0 4.0005 270)
			(size 1.1938 0.508)
			(layers "F.Cu" "F.Mask" "F.Paste")
			(net "P12V")
		)
		(pad "12" smd rect
			(at 3.4036 4.0005 270)
			(size 1.1938 0.508)
			(layers "F.Cu" "F.Mask" "F.Paste")
			(net "P12V")
		)
		(pad "13" smd rect
			(at 0 4.8006 270)
			(size 1.1938 0.508)
			(layers "F.Cu" "F.Mask" "F.Paste")
			(net "GND")
		)
		(pad "14" smd rect
			(at 3.4036 4.8006 270)
			(size 1.1938 0.508)
			(layers "F.Cu" "F.Mask" "F.Paste")
			(net "GND")
		)
		(pad "15" smd rect
			(at 0 5.6007 270)
			(size 1.1938 0.508)
			(layers "F.Cu" "F.Mask" "F.Paste")
			(net "SMB_SLOTX24_STBY_LVC3_SDA_R2")
		)
		(pad "16" smd rect
			(at 3.4036 5.6007 270)
			(size 1.1938 0.508)
			(layers "F.Cu" "F.Mask" "F.Paste")
			(net "IRQ_OOB_MGMT_RISER_ALERT_N")
		)
		(pad "17" smd rect
			(at 0 6.4008 270)
			(size 1.1938 0.508)
			(layers "F.Cu" "F.Mask" "F.Paste")
			(net "SMB_SLOTX24_STBY_LVC3_SCL_R2")
		)
		(pad "18" smd rect
			(at 3.4036 6.4008 270)
			(size 1.1938 0.508)
			(layers "F.Cu" "F.Mask" "F.Paste")
			(net "FM_SLT_CFG1")
		)
		(pad "19" smd rect
			(at 0 7.2009 270)
			(size 1.1938 0.508)
			(layers "F.Cu" "F.Mask" "F.Paste")
			(net "FM_SLT_CFG0")
		)
		(pad "20" smd rect
			(at 3.4036 7.2009 270)
			(size 1.1938 0.508)
			(layers "F.Cu" "F.Mask" "F.Paste")
			(net "FM_PWRBRK_SLOT_N")
		)
		(pad "21" smd rect
			(at 0 8.001 270)
			(size 1.1938 0.508)
			(layers "F.Cu" "F.Mask" "F.Paste")
			(net "P3V3")
		)
		(pad "22" smd rect
			(at 3.4036 8.001 270)
			(size 1.1938 0.508)
			(layers "F.Cu" "F.Mask" "F.Paste")
			(net "P3V3")
		)
		(pad "23" smd rect
			(at 0 8.8011 270)
			(size 1.1938 0.508)
			(layers "F.Cu" "F.Mask" "F.Paste")
			(net "P3V3")
		)
		(pad "24" smd rect
			(at 3.4036 8.8011 270)
			(size 1.1938 0.508)
			(layers "F.Cu" "F.Mask" "F.Paste")
			(net "P3V3")
		)
		(pad "25" smd rect
			(at 0 9.6012 270)
			(size 1.1938 0.508)
			(layers "F.Cu" "F.Mask" "F.Paste")
			(net "P3V3_STBY")
		)
		(pad "26" smd rect
			(at 3.4036 9.6012 270)
			(size 1.1938 0.508)
			(layers "F.Cu" "F.Mask" "F.Paste")
			(net "GND")
		)
		(pad "27" smd rect
			(at 0 10.4013 270)
			(size 1.1938 0.508)
			(layers "F.Cu" "F.Mask" "F.Paste")
			(net "PU_PCH_TLS_ENABLE_STRAP")
		)
		(pad "28" smd rect
			(at 3.4036 10.4013 270)
			(size 1.1938 0.508)
			(layers "F.Cu" "F.Mask" "F.Paste")
			(net "FM_PE_SLOTX24_WAKE_N")
		)
		(pad "29" smd rect
			(at 0 11.2014 270)
			(size 1.1938 0.508)
			(layers "F.Cu" "F.Mask" "F.Paste")
			(net "RST_PCIE_RISER1_PERST_R_N")
		)
		(pad "30" smd rect
			(at 3.4036 11.2014 270)
			(size 1.1938 0.508)
			(layers "F.Cu" "F.Mask" "F.Paste")
			(net "SMB_HOST_STBY_LVC3_SDA_R5")
		)
		(pad "31" smd rect
			(at 0 12.0015 270)
			(size 1.1938 0.508)
			(layers "F.Cu" "F.Mask" "F.Paste")
			(net "GND")
		)
		(pad "32" smd rect
			(at 3.4036 12.0015 270)
			(size 1.1938 0.508)
			(layers "F.Cu" "F.Mask" "F.Paste")
			(net "SMB_HOST_STBY_LVC3_SCL_R5")
		)
		(pad "33" smd rect
			(at 0 12.8016 270)
			(size 1.1938 0.508)
			(layers "F.Cu" "F.Mask" "F.Paste")
			(net "CLK_100M_PCH_SLOTX24_S5_DP")
		)
		(pad "34" smd rect
			(at 3.4036 12.8016 270)
			(size 1.1938 0.508)
			(layers "F.Cu" "F.Mask" "F.Paste")
			(net "GND")
		)
		(pad "35" smd rect
			(at 0 13.6017 270)
			(size 1.1938 0.508)
			(layers "F.Cu" "F.Mask" "F.Paste")
			(net "CLK_100M_PCH_SLOTX24_S5_DN")
		)
		(pad "36" smd rect
			(at 3.4036 13.6017 270)
			(size 1.1938 0.508)
			(layers "F.Cu" "F.Mask" "F.Paste")
			(net "CLK_100M_PCH_SLOTX24_S4_DP")
		)
		(pad "37" smd rect
			(at 0 14.4018 270)
			(size 1.1938 0.508)
			(layers "F.Cu" "F.Mask" "F.Paste")
			(net "GND")
		)
		(pad "38" smd rect
			(at 3.4036 14.4018 270)
			(size 1.1938 0.508)
			(layers "F.Cu" "F.Mask" "F.Paste")
			(net "CLK_100M_PCH_SLOTX24_S4_DN")
		)
		(pad "39" smd rect
			(at 0 15.2019 270)
			(size 1.1938 0.508)
			(layers "F.Cu" "F.Mask" "F.Paste")
			(net "CLK_100M_PCH_SLOTX24_S0_DP")
		)
		(pad "40" smd rect
			(at 3.4036 15.2019 270)
			(size 1.1938 0.508)
			(layers "F.Cu" "F.Mask" "F.Paste")
			(net "GND")
		)
		(pad "41" smd rect
			(at 0 16.002 270)
			(size 1.1938 0.508)
			(layers "F.Cu" "F.Mask" "F.Paste")
			(net "CLK_100M_PCH_SLOTX24_S0_DN")
		)
		(pad "42" smd rect
			(at 3.4036 16.002 270)
			(size 1.1938 0.508)
			(layers "F.Cu" "F.Mask" "F.Paste")
			(net "CLK_100M_PCH_SLOTX24_S1_DP")
		)
		(pad "43" smd rect
			(at 0 16.8021 270)
			(size 1.1938 0.508)
			(layers "F.Cu" "F.Mask" "F.Paste")
			(net "GND")
		)
		(pad "44" smd rect
			(at 3.4036 16.8021 270)
			(size 1.1938 0.508)
			(layers "F.Cu" "F.Mask" "F.Paste")
			(net "CLK_100M_PCH_SLOTX24_S1_DN")
		)
		(pad "45" smd rect
			(at 0 17.6022 270)
			(size 1.1938 0.508)
			(layers "F.Cu" "F.Mask" "F.Paste")
			(net "CLK_100M_PCH_SLOTX24_S3_DP")
		)
		(pad "46" smd rect
			(at 3.4036 17.6022 270)
			(size 1.1938 0.508)
			(layers "F.Cu" "F.Mask" "F.Paste")
			(net "GND")
		)
	)
)
